(kicad_pcb
	(version 20241229)
	(generator "pcbnew")
	(generator_version "9.0")
	(general
		(thickness 1.6296)
		(legacy_teardrops no)
	)
	(paper "A3")
	(title_block
		(title "Thunderbolt to 10GbE adapter")
		(date "2026-04-21")
		(rev "1.1.0")
		(company "Antmicro Ltd")
		(comment 1 "www.antmicro.com")
		(comment 9 "footprints 672-676 of 703")
	)
	(layers
		(0 "F.Cu" signal)
		(4 "In1.Cu" signal)
		(6 "In2.Cu" signal)
		(8 "In3.Cu" signal)
		(10 "In4.Cu" signal)
		(12 "In5.Cu" signal)
		(14 "In6.Cu" signal)
		(2 "B.Cu" signal)
		(9 "F.Adhes" user "F.Adhesive")
		(11 "B.Adhes" user "B.Adhesive")
		(13 "F.Paste" user)
		(15 "B.Paste" user)
		(5 "F.SilkS" user "F.Silkscreen")
		(7 "B.SilkS" user "B.Silkscreen")
		(1 "F.Mask" user)
		(3 "B.Mask" user)
		(17 "Dwgs.User" user "User.Drawings")
		(19 "Cmts.User" user "User.Comments")
		(21 "Eco1.User" user "User.Eco1")
		(23 "Eco2.User" user "User.Eco2")
		(25 "Edge.Cuts" user)
		(27 "Margin" user)
		(31 "F.CrtYd" user "F.Courtyard")
		(29 "B.CrtYd" user "B.Courtyard")
		(35 "F.Fab" user)
		(33 "B.Fab" user)
	)
	(footprint "antmicro-footprints:C_0402_1005Metric"
		(layer "B.Cu")
		(at 153.031866 77.260118 180)
		(descr "Capacitor SMD 0402")
		(tags "capacitor SMD 0402")
		(property "Reference" "C236"
			(at -21.168135 -9.464883 0)
			(layer "B.SilkS")
			(effects
				(font
					(size 0.7 0.7)
					(thickness 0.15)
				)
				(justify mirror)
			)
		)
		(property "Value" "C_1u_25V_0402"
			(at -1.022927 -2.155213 0)
			(layer "B.Fab")
			(effects
				(font
					(size 0.7 0.7)
					(thickness 0.15)
				)
				(justify left bottom mirror)
			)
		)
		(property "Datasheet" "https://www.murata.com/products/productdetail?partno=GRM155R61E105KE11%23"
			(at 0 0 0)
			(layer "B.Fab")
			(hide yes)
			(effects
				(font
					(size 1.27 1.27)
					(thickness 0.15)
				)
				(justify mirror)
			)
		)
		(property "Description" "SMD Multilayer Ceramic Capacitor, 1 µF, 25 V, 0402 [1005 Metric], ± 10%, X5R, GRM Series"
			(at 0 0 0)
			(layer "B.Fab")
			(hide yes)
			(effects
				(font
					(size 1.27 1.27)
					(thickness 0.15)
				)
				(justify mirror)
			)
		)
		(property "MPN" "GRM155R61E105KE11J"
			(at 0 0 180)
			(unlocked yes)
			(layer "B.Fab")
			(hide yes)
			(effects
				(font
					(size 1 1)
					(thickness 0.15)
				)
				(justify mirror)
			)
		)
		(property "Manufacturer" "Murata"
			(at 0 0 180)
			(unlocked yes)
			(layer "B.Fab")
			(hide yes)
			(effects
				(font
					(size 1 1)
					(thickness 0.15)
				)
				(justify mirror)
			)
		)
		(property "License" "Apache-2.0"
			(at 0 0 180)
			(unlocked yes)
			(layer "B.Fab")
			(hide yes)
			(effects
				(font
					(size 1 1)
					(thickness 0.15)
				)
				(justify mirror)
			)
		)
		(property "Author" "Antmicro"
			(at 0 0 180)
			(unlocked yes)
			(layer "B.Fab")
			(hide yes)
			(effects
				(font
					(size 1 1)
					(thickness 0.15)
				)
				(justify mirror)
			)
		)
		(property "Val" "1u"
			(at 0 0 180)
			(unlocked yes)
			(layer "B.Fab")
			(hide yes)
			(effects
				(font
					(size 1 1)
					(thickness 0.15)
				)
				(justify mirror)
			)
		)
		(property "Voltage" "25V"
			(at 0 0 180)
			(unlocked yes)
			(layer "B.Fab")
			(hide yes)
			(effects
				(font
					(size 1 1)
					(thickness 0.15)
				)
				(justify mirror)
			)
		)
		(property "Dielectric" "X5R"
			(at 0 0 180)
			(unlocked yes)
			(layer "B.Fab")
			(hide yes)
			(effects
				(font
					(size 1 1)
					(thickness 0.15)
				)
				(justify mirror)
			)
		)
		(sheetname "/X710-AT2 power/")
		(sheetfile "x710-at2-power.kicad_sch")
		(attr smd)
		(fp_rect
			(start -0.925 0.47)
			(end 0.925 -0.47)
			(stroke
				(width 0.05)
				(type default)
			)
			(fill no)
			(layer "B.CrtYd")
		)
		(fp_line
			(start 0.504 0.25)
			(end 0.504 -0.248)
			(stroke
				(width 0.15)
				(type solid)
			)
			(layer "B.Fab")
		)
		(fp_line
			(start 0.504 -0.248)
			(end -0.494 -0.248)
			(stroke
				(width 0.15)
				(type solid)
			)
			(layer "B.Fab")
		)
		(fp_line
			(start -0.494 0.25)
			(end 0.504 0.25)
			(stroke
				(width 0.15)
				(type solid)
			)
			(layer "B.Fab")
		)
		(fp_line
			(start -0.494 -0.248)
			(end -0.494 0.25)
			(stroke
				(width 0.15)
				(type solid)
			)
			(layer "B.Fab")
		)
		(fp_text user "${REFERENCE}"
			(at -0.939 -4.599 0)
			(layer "B.Fab")
			(effects
				(font
					(size 0.7 0.7)
					(thickness 0.15)
				)
				(justify left bottom mirror)
			)
		)
		(fp_text user "License: Apache-2.0"
			(at -0.939 -5.799 0)
			(layer "B.Fab")
			(effects
				(font
					(size 0.7 0.7)
					(thickness 0.15)
				)
				(justify left bottom mirror)
			)
		)
		(fp_text user "Author: Antmicro"
			(at -0.939 -3.399 0)
			(layer "B.Fab")
			(effects
				(font
					(size 0.7 0.7)
					(thickness 0.15)
				)
				(justify left bottom mirror)
			)
		)
		(pad "1" smd roundrect
			(at -0.48 0 180)
			(size 0.59 0.64)
			(layers "B.Cu" "B.Mask" "B.Paste")
			(roundrect_rratio 0.25)
			(net 23 "GND")
			(pintype "passive")
		)
		(pad "2" smd roundrect
			(at 0.48 0 180)
			(size 0.59 0.64)
			(layers "B.Cu" "B.Mask" "B.Paste")
			(roundrect_rratio 0.25)
			(net 1 "VCCA")
			(pintype "passive")
		)
	)
	(footprint "antmicro-footprints:C_0402_1005Metric"
		(layer "B.Cu")
		(at 145.631866 77.260117 180)
		(descr "Capacitor SMD 0402")
		(tags "capacitor SMD 0402")
		(property "Reference" "C245"
			(at -17.768134 -9.464883 0)
			(layer "B.SilkS")
			(effects
				(font
					(size 0.7 0.7)
					(thickness 0.15)
				)
				(justify mirror)
			)
		)
		(property "Value" "C_1u_25V_0402"
			(at -1.022927 -2.155213 0)
			(layer "B.Fab")
			(effects
				(font
					(size 0.7 0.7)
					(thickness 0.15)
				)
				(justify left bottom mirror)
			)
		)
		(property "Datasheet" "https://www.murata.com/products/productdetail?partno=GRM155R61E105KE11%23"
			(at 0 0 0)
			(layer "B.Fab")
			(hide yes)
			(effects
				(font
					(size 1.27 1.27)
					(thickness 0.15)
				)
				(justify mirror)
			)
		)
		(property "Description" "SMD Multilayer Ceramic Capacitor, 1 µF, 25 V, 0402 [1005 Metric], ± 10%, X5R, GRM Series"
			(at 0 0 0)
			(layer "B.Fab")
			(hide yes)
			(effects
				(font
					(size 1.27 1.27)
					(thickness 0.15)
				)
				(justify mirror)
			)
		)
		(property "MPN" "GRM155R61E105KE11J"
			(at 0 0 180)
			(unlocked yes)
			(layer "B.Fab")
			(hide yes)
			(effects
				(font
					(size 1 1)
					(thickness 0.15)
				)
				(justify mirror)
			)
		)
		(property "Manufacturer" "Murata"
			(at 0 0 180)
			(unlocked yes)
			(layer "B.Fab")
			(hide yes)
			(effects
				(font
					(size 1 1)
					(thickness 0.15)
				)
				(justify mirror)
			)
		)
		(property "License" "Apache-2.0"
			(at 0 0 180)
			(unlocked yes)
			(layer "B.Fab")
			(hide yes)
			(effects
				(font
					(size 1 1)
					(thickness 0.15)
				)
				(justify mirror)
			)
		)
		(property "Author" "Antmicro"
			(at 0 0 180)
			(unlocked yes)
			(layer "B.Fab")
			(hide yes)
			(effects
				(font
					(size 1 1)
					(thickness 0.15)
				)
				(justify mirror)
			)
		)
		(property "Val" "1u"
			(at 0 0 180)
			(unlocked yes)
			(layer "B.Fab")
			(hide yes)
			(effects
				(font
					(size 1 1)
					(thickness 0.15)
				)
				(justify mirror)
			)
		)
		(property "Voltage" "25V"
			(at 0 0 180)
			(unlocked yes)
			(layer "B.Fab")
			(hide yes)
			(effects
				(font
					(size 1 1)
					(thickness 0.15)
				)
				(justify mirror)
			)
		)
		(property "Dielectric" "X5R"
			(at 0 0 180)
			(unlocked yes)
			(layer "B.Fab")
			(hide yes)
			(effects
				(font
					(size 1 1)
					(thickness 0.15)
				)
				(justify mirror)
			)
		)
		(sheetname "/X710-AT2 power/")
		(sheetfile "x710-at2-power.kicad_sch")
		(attr smd)
		(fp_rect
			(start -0.925 0.47)
			(end 0.925 -0.47)
			(stroke
				(width 0.05)
				(type default)
			)
			(fill no)
			(layer "B.CrtYd")
		)
		(fp_line
			(start 0.504 0.25)
			(end 0.504 -0.248)
			(stroke
				(width 0.15)
				(type solid)
			)
			(layer "B.Fab")
		)
		(fp_line
			(start 0.504 -0.248)
			(end -0.494 -0.248)
			(stroke
				(width 0.15)
				(type solid)
			)
			(layer "B.Fab")
		)
		(fp_line
			(start -0.494 0.25)
			(end 0.504 0.25)
			(stroke
				(width 0.15)
				(type solid)
			)
			(layer "B.Fab")
		)
		(fp_line
			(start -0.494 -0.248)
			(end -0.494 0.25)
			(stroke
				(width 0.15)
				(type solid)
			)
			(layer "B.Fab")
		)
		(fp_text user "License: Apache-2.0"
			(at -0.939 -5.799 0)
			(layer "B.Fab")
			(effects
				(font
					(size 0.7 0.7)
					(thickness 0.15)
				)
				(justify left bottom mirror)
			)
		)
		(fp_text user "Author: Antmicro"
			(at -0.939 -3.399 0)
			(layer "B.Fab")
			(effects
				(font
					(size 0.7 0.7)
					(thickness 0.15)
				)
				(justify left bottom mirror)
			)
		)
		(fp_text user "${REFERENCE}"
			(at -0.939 -4.599 0)
			(layer "B.Fab")
			(effects
				(font
					(size 0.7 0.7)
					(thickness 0.15)
				)
				(justify left bottom mirror)
			)
		)
		(pad "1" smd roundrect
			(at -0.48 0 180)
			(size 0.59 0.64)
			(layers "B.Cu" "B.Mask" "B.Paste")
			(roundrect_rratio 0.25)
			(net 23 "GND")
			(pintype "passive")
		)
		(pad "2" smd roundrect
			(at 0.48 0 180)
			(size 0.59 0.64)
			(layers "B.Cu" "B.Mask" "B.Paste")
			(roundrect_rratio 0.25)
			(net 1 "VCCA")
			(pintype "passive")
		)
	)
	(footprint "antmicro-footprints:C_0402_1005Metric"
		(layer "B.Cu")
		(at 127.524999 120.050001 -90)
		(descr "Capacitor SMD 0402")
		(tags "capacitor SMD 0402")
		(property "Reference" "C56"
			(at -7.700002 -21.900002 90)
			(layer "B.SilkS")
			(effects
				(font
					(size 0.7 0.7)
					(thickness 0.15)
				)
				(justify mirror)
			)
		)
		(property "Value" "C_1u_0402"
			(at -1.022927 -2.155213 90)
			(layer "B.Fab")
			(effects
				(font
					(size 0.7 0.7)
					(thickness 0.15)
				)
				(justify left bottom mirror)
			)
		)
		(property "Datasheet" "https://product.tdk.com/en/search/capacitor/ceramic/mlcc/info?part_no=C1005X6S1A105K050BC"
			(at 0 0 90)
			(layer "B.Fab")
			(hide yes)
			(effects
				(font
					(size 1.27 1.27)
					(thickness 0.15)
				)
				(justify mirror)
			)
		)
		(property "Description" "SMD Multilayer Ceramic Capacitor, 1 µF, 10 V, 0402 [1005 Metric], ± 10%, X6S, C"
			(at 0 0 90)
			(layer "B.Fab")
			(hide yes)
			(effects
				(font
					(size 1.27 1.27)
					(thickness 0.15)
				)
				(justify mirror)
			)
		)
		(property "MPN" "C1005X6S1A105K050BC"
			(at 0 0 270)
			(unlocked yes)
			(layer "B.Fab")
			(hide yes)
			(effects
				(font
					(size 1 1)
					(thickness 0.15)
				)
				(justify mirror)
			)
		)
		(property "Manufacturer" "TDK"
			(at 0 0 270)
			(unlocked yes)
			(layer "B.Fab")
			(hide yes)
			(effects
				(font
					(size 1 1)
					(thickness 0.15)
				)
				(justify mirror)
			)
		)
		(property "License" "Apache-2.0"
			(at 0 0 270)
			(unlocked yes)
			(layer "B.Fab")
			(hide yes)
			(effects
				(font
					(size 1 1)
					(thickness 0.15)
				)
				(justify mirror)
			)
		)
		(property "Val" "1u"
			(at 0 0 270)
			(unlocked yes)
			(layer "B.Fab")
			(hide yes)
			(effects
				(font
					(size 1 1)
					(thickness 0.15)
				)
				(justify mirror)
			)
		)
		(property "Voltage" ""
			(at 0 0 270)
			(unlocked yes)
			(layer "B.Fab")
			(hide yes)
			(effects
				(font
					(size 1 1)
					(thickness 0.15)
				)
				(justify mirror)
			)
		)
		(property "Dielectric" ""
			(at 0 0 270)
			(unlocked yes)
			(layer "B.Fab")
			(hide yes)
			(effects
				(font
					(size 1 1)
					(thickness 0.15)
				)
				(justify mirror)
			)
		)
		(property "Author" "Antmicro"
			(at 0 0 270)
			(unlocked yes)
			(layer "B.Fab")
			(hide yes)
			(effects
				(font
					(size 1 1)
					(thickness 0.15)
				)
				(justify mirror)
			)
		)
		(sheetname "/TB Controller - Power/")
		(sheetfile "tb-power.kicad_sch")
		(attr smd)
		(fp_rect
			(start -0.925 0.47)
			(end 0.925 -0.47)
			(stroke
				(width 0.05)
				(type default)
			)
			(fill no)
			(layer "B.CrtYd")
		)
		(fp_line
			(start -0.494 0.25)
			(end 0.504 0.25)
			(stroke
				(width 0.15)
				(type solid)
			)
			(layer "B.Fab")
		)
		(fp_line
			(start 0.504 0.25)
			(end 0.504 -0.248)
			(stroke
				(width 0.15)
				(type solid)
			)
			(layer "B.Fab")
		)
		(fp_line
			(start -0.494 -0.248)
			(end -0.494 0.25)
			(stroke
				(width 0.15)
				(type solid)
			)
			(layer "B.Fab")
		)
		(fp_line
			(start 0.504 -0.248)
			(end -0.494 -0.248)
			(stroke
				(width 0.15)
				(type solid)
			)
			(layer "B.Fab")
		)
		(fp_text user "Author: Antmicro"
			(at -0.939 -3.399 90)
			(layer "B.Fab")
			(effects
				(font
					(size 0.7 0.7)
					(thickness 0.15)
				)
				(justify left bottom mirror)
			)
		)
		(fp_text user "License: Apache-2.0"
			(at -0.939 -5.799 90)
			(layer "B.Fab")
			(effects
				(font
					(size 0.7 0.7)
					(thickness 0.15)
				)
				(justify left bottom mirror)
			)
		)
		(fp_text user "${REFERENCE}"
			(at -0.939 -4.599 90)
			(layer "B.Fab")
			(effects
				(font
					(size 0.7 0.7)
					(thickness 0.15)
				)
				(justify left bottom mirror)
			)
		)
		(pad "1" smd roundrect
			(at -0.48 0 270)
			(size 0.59 0.64)
			(layers "B.Cu" "B.Mask" "B.Paste")
			(roundrect_rratio 0.25)
			(net 23 "GND")
			(pintype "passive")
		)
		(pad "2" smd roundrect
			(at 0.48 0 270)
			(size 0.59 0.64)
			(layers "B.Cu" "B.Mask" "B.Paste")
			(roundrect_rratio 0.25)
			(net 402 "Net-(C52-Pad2)")
			(pintype "passive")
		)
	)
	(footprint "antmicro-footprints:R_0402_1005Metric"
		(layer "B.Cu")
		(at 130.9 131.1 90)
		(descr "Resistor SMD 0402")
		(tags "resistor SMD 0402")
		(property "Reference" "R54"
			(at 8.1 20.250001 270)
			(layer "B.SilkS")
			(effects
				(font
					(size 0.7 0.7)
					(thickness 0.15)
				)
				(justify mirror)
			)
		)
		(property "Value" "R_1M_0402"
			(at -1.011843 -1.772047 270)
			(layer "B.Fab")
			(effects
				(font
					(size 0.7 0.7)
					(thickness 0.15)
				)
				(justify left bottom mirror)
			)
		)
		(property "Datasheet" "https://www.bourns.com/docs/product-datasheets/cr.pdf"
			(at 0 0 270)
			(layer "B.Fab")
			(hide yes)
			(effects
				(font
					(size 1.27 1.27)
					(thickness 0.15)
				)
				(justify mirror)
			)
		)
		(property "Description" "SMD Chip Resistor, 1 Mohm, ± 1%, 62.5 mW, 0402 [1005 Metric], Thick Film, General Purpose"
			(at 0 0 270)
			(layer "B.Fab")
			(hide yes)
			(effects
				(font
					(size 1.27 1.27)
					(thickness 0.15)
				)
				(justify mirror)
			)
		)
		(property "MPN" "CR0402-FX-1004GLF"
			(at 0 0 90)
			(unlocked yes)
			(layer "B.Fab")
			(hide yes)
			(effects
				(font
					(size 1 1)
					(thickness 0.15)
				)
				(justify mirror)
			)
		)
		(property "Manufacturer" "Bourns"
			(at 0 0 90)
			(unlocked yes)
			(layer "B.Fab")
			(hide yes)
			(effects
				(font
					(size 1 1)
					(thickness 0.15)
				)
				(justify mirror)
			)
		)
		(property "License" "Apache-2.0"
			(at 0 0 90)
			(unlocked yes)
			(layer "B.Fab")
			(hide yes)
			(effects
				(font
					(size 1 1)
					(thickness 0.15)
				)
				(justify mirror)
			)
		)
		(property "Val" "1M"
			(at 0 0 90)
			(unlocked yes)
			(layer "B.Fab")
			(hide yes)
			(effects
				(font
					(size 1 1)
					(thickness 0.15)
				)
				(justify mirror)
			)
		)
		(property "Tolerance" "1%"
			(at 0 0 90)
			(unlocked yes)
			(layer "B.Fab")
			(hide yes)
			(effects
				(font
					(size 1 1)
					(thickness 0.15)
				)
				(justify mirror)
			)
		)
		(property "Author" "Antmicro"
			(at 0 0 90)
			(unlocked yes)
			(layer "B.Fab")
			(hide yes)
			(effects
				(font
					(size 1 1)
					(thickness 0.15)
				)
				(justify mirror)
			)
		)
		(sheetname "/TB Controller/")
		(sheetfile "tb.kicad_sch")
		(attr smd)
		(fp_rect
			(start -0.925 0.47)
			(end 0.925 -0.47)
			(stroke
				(width 0.05)
				(type default)
			)
			(fill no)
			(layer "B.CrtYd")
		)
		(fp_rect
			(start -0.5 0.25)
			(end 0.5 -0.25)
			(stroke
				(width 0.15)
				(type solid)
			)
			(fill no)
			(layer "B.Fab")
		)
		(fp_text user "License: Apache-2.0"
			(at -0.95 -5.169 270)
			(layer "B.Fab")
			(effects
				(font
					(size 0.7 0.7)
					(thickness 0.15)
				)
				(justify left bottom mirror)
			)
		)
		(fp_text user "Author: Antmicro"
			(at -0.95 -4.169 270)
			(layer "B.Fab")
			(effects
				(font
					(size 0.7 0.7)
					(thickness 0.15)
				)
				(justify left bottom mirror)
			)
		)
		(fp_text user "${REFERENCE}"
			(at -0.95 -3.168 270)
			(layer "B.Fab")
			(effects
				(font
					(size 0.7 0.7)
					(thickness 0.15)
				)
				(justify left bottom mirror)
			)
		)
		(pad "1" smd roundrect
			(at -0.48 0 90)
			(size 0.59 0.64)
			(layers "B.Cu" "B.Mask" "B.Paste")
			(roundrect_rratio 0.25)
			(net 23 "GND")
			(pintype "passive")
		)
		(pad "2" smd roundrect
			(at 0.48 0 90)
			(size 0.59 0.64)
			(layers "B.Cu" "B.Mask" "B.Paste")
			(roundrect_rratio 0.25)
			(net 376 "/PD and TB DC-DC/LSX_1.LSX_P2R")
			(pintype "passive")
		)
	)
	(footprint "antmicro-footprints:R_0402_1005Metric"
		(layer "B.Cu")
		(at 152.681866 87.635117 -90)
		(descr "Resistor SMD 0402")
		(tags "resistor SMD 0402")
		(property "Reference" "R174"
			(at 8.564883 -17.718134 90)
			(layer "B.SilkS")
			(effects
				(font
					(size 0.7 0.7)
					(thickness 0.15)
				)
				(justify mirror)
			)
		)
		(property "Value" "R_1k_0402"
			(at -1.011843 -1.772047 90)
			(layer "B.Fab")
			(effects
				(font
					(size 0.7 0.7)
					(thickness 0.15)
				)
				(justify left bottom mirror)
			)
		)
		(property "Datasheet" "https://www.bourns.com/docs/product-datasheets/cr.pdf"
			(at 0 0 90)
			(layer "B.Fab")
			(hide yes)
			(effects
				(font
					(size 1.27 1.27)
					(thickness 0.15)
				)
				(justify mirror)
			)
		)
		(property "Description" "SMD Chip Resistor, 1 kohm, ± 1%, 63 mW, 0402 [1005 Metric], Thick Film, General Purpose"
			(at 0 0 90)
			(layer "B.Fab")
			(hide yes)
			(effects
				(font
					(size 1.27 1.27)
					(thickness 0.15)
				)
				(justify mirror)
			)
		)
		(property "MPN" "CR0402-FX-1001GLF"
			(at 0 0 270)
			(unlocked yes)
			(layer "B.Fab")
			(hide yes)
			(effects
				(font
					(size 1 1)
					(thickness 0.15)
				)
				(justify mirror)
			)
		)
		(property "Manufacturer" "Bourns"
			(at 0 0 270)
			(unlocked yes)
			(layer "B.Fab")
			(hide yes)
			(effects
				(font
					(size 1 1)
					(thickness 0.15)
				)
				(justify mirror)
			)
		)
		(property "License" "Apache-2.0"
			(at 0 0 270)
			(unlocked yes)
			(layer "B.Fab")
			(hide yes)
			(effects
				(font
					(size 1 1)
					(thickness 0.15)
				)
				(justify mirror)
			)
		)
		(property "Author" "Antmicro"
			(at 0 0 270)
			(unlocked yes)
			(layer "B.Fab")
			(hide yes)
			(effects
				(font
					(size 1 1)
					(thickness 0.15)
				)
				(justify mirror)
			)
		)
		(property "Val" "1k"
			(at 0 0 270)
			(unlocked yes)
			(layer "B.Fab")
			(hide yes)
			(effects
				(font
					(size 1 1)
					(thickness 0.15)
				)
				(justify mirror)
			)
		)
		(property "Tolerance" "1%"
			(at 0 0 270)
			(unlocked yes)
			(layer "B.Fab")
			(hide yes)
			(effects
				(font
					(size 1 1)
					(thickness 0.15)
				)
				(justify mirror)
			)
		)
		(sheetname "/X710-AT2 Misc/")
		(sheetfile "x710-at2-mics.kicad_sch")
		(attr smd)
		(fp_rect
			(start -0.925 0.47)
			(end 0.925 -0.47)
			(stroke
				(width 0.05)
				(type default)
			)
			(fill no)
			(layer "B.CrtYd")
		)
		(fp_rect
			(start -0.5 0.25)
			(end 0.5 -0.25)
			(stroke
				(width 0.15)
				(type solid)
			)
			(fill no)
			(layer "B.Fab")
		)
		(fp_text user "License: Apache-2.0"
			(at -0.95 -5.169 90)
			(layer "B.Fab")
			(effects
				(font
					(size 0.7 0.7)
					(thickness 0.15)
				)
				(justify left bottom mirror)
			)
		)
		(fp_text user "Author: Antmicro"
			(at -0.95 -4.169 90)
			(layer "B.Fab")
			(effects
				(font
					(size 0.7 0.7)
					(thickness 0.15)
				)
				(justify left bottom mirror)
			)
		)
		(fp_text user "${REFERENCE}"
			(at -0.95 -3.168 90)
			(layer "B.Fab")
			(effects
				(font
					(size 0.7 0.7)
					(thickness 0.15)
				)
				(justify left bottom mirror)
			)
		)
		(pad "1" smd roundrect
			(at -0.48 0 270)
			(size 0.59 0.64)
			(layers "B.Cu" "B.Mask" "B.Paste")
			(roundrect_rratio 0.25)
			(net 84 "/X710-AT2 Misc/RSVDL33")
			(pintype "passive")
		)
		(pad "2" smd roundrect
			(at 0.48 0 270)
			(size 0.59 0.64)
			(layers "B.Cu" "B.Mask" "B.Paste")
			(roundrect_rratio 0.25)
			(net 18 "+1V88")
			(pintype "passive")
		)
	)
)
